# T6G (Grand Teton) — schematic netlist excerpt (pin names and nets, part order shuffled) for the footprints in the layout excerpt that follows; sources: Cadence DE-HDL packaged netlist, KiCad conversion of 04192023_DAF0TMB3IC0_F0TG_MB_C_brd_V02_OCP.brd

PR8008  Q_RES  0 5% CHIP  pkg 0402LF  page 200 : A = SVID_PVDDCR_CPU1_P0_SVD_R ; B = SVID_PVDDCR_CPU1_P0_SVD_R1
R1056  Q_RES  1K 1% EMPTY  pkg 0201LF  page 298 : A = RT_CPU0_P2_ADDR3 ; B = GND
PC172  Q_CAP  2.2UF 10V 10% X6S  pkg C0402  page 206 : A = PVDDIO_P0_VCC3 ; B = GND

(kicad_pcb
	(version 20260206)
	(generator "pcbnew")
	(generator_version "10.0")
	(general
		(thickness 1.6)
		(legacy_teardrops no)
	)
	(paper "A4")
	(title_block
		(title "04192023_DAF0TMB3IC0_F0TG_MB_C_brd_V02_OCP.brd")
		(comment 1 "Grand Teton / footprints 1705-1707 of 8354")
	)
	(layers
		(0 "F.Cu" signal "TOP")
		(4 "In1.Cu" signal "GND")
		(6 "In2.Cu" signal "IN1")
		(8 "In3.Cu" signal "GND1")
		(10 "In4.Cu" signal "IN2")
		(12 "In5.Cu" signal "GND2")
		(14 "In6.Cu" signal "IN3")
		(16 "In7.Cu" signal "GND3")
		(18 "In8.Cu" signal "VCC")
		(20 "In9.Cu" signal "VCC1")
		(22 "In10.Cu" signal "GND4")
		(24 "In11.Cu" signal "IN4")
		(26 "In12.Cu" signal "GND5")
		(28 "In13.Cu" signal "IN5")
		(30 "In14.Cu" signal "GND6")
		(32 "In15.Cu" signal "IN6")
		(34 "In16.Cu" signal "GND7")
		(2 "B.Cu" signal "BOTTOM")
		(9 "F.Adhes" user "F.Adhesive")
		(11 "B.Adhes" user "B.Adhesive")
		(13 "F.Paste" user "Package Geometry/Pastemask Top")
		(15 "B.Paste" user "Package Geometry/Pastemask Bottom")
		(5 "F.SilkS" user "Ref Des/Silkscreen Top")
		(7 "B.SilkS" user "Ref Des/Silkscreen Bottom")
		(1 "F.Mask" user "Board Geometry/Soldermask Top")
		(3 "B.Mask" user "Board Geometry/Soldermask Bottom")
		(17 "Dwgs.User" user "User.Drawings")
		(19 "Cmts.User" user "User.Comments")
		(21 "Eco1.User" user "User.Eco1")
		(23 "Eco2.User" user "User.Eco2")
		(25 "Edge.Cuts" user "Board Geometry/Outline")
		(27 "Margin" user)
		(31 "F.CrtYd" user "Package Geometry/Place Bound Top")
		(29 "B.CrtYd" user "Package Geometry/Place Bound Bottom")
		(35 "F.Fab" user "Ref Des/Assembly Top")
		(33 "B.Fab" user "Ref Des/Assembly Bottom")
	)
	(footprint ""
		(layer "F.Cu")
		(at 304.419 -358.14)
		(property "Reference" "PR8008"
			(at 0 0 0)
			(layer "F.SilkS")
			(hide yes)
			(effects
				(font
					(size 1.27 1.27)
				)
			)
		)
		(property "Value" ""
			(at 0 0 0)
			(layer "F.Fab")
			(effects
				(font
					(size 1.27 1.27)
				)
			)
		)
		(duplicate_pad_numbers_are_jumpers no)
		(fp_line
			(start -0.7874 -0.4064)
			(end 0.7874 -0.4064)
			(stroke
				(width 0.1524)
				(type default)
			)
			(layer "F.SilkS")
		)
		(fp_line
			(start -0.7874 0.4064)
			(end -0.7874 -0.4064)
			(stroke
				(width 0.1524)
				(type default)
			)
			(layer "F.SilkS")
		)
		(fp_line
			(start 0.7874 -0.4064)
			(end 0.7874 0.4064)
			(stroke
				(width 0.1524)
				(type default)
			)
			(layer "F.SilkS")
		)
		(fp_line
			(start 0.7874 0.4064)
			(end -0.7874 0.4064)
			(stroke
				(width 0.1524)
				(type default)
			)
			(layer "F.SilkS")
		)
		(fp_line
			(start -0.67945 -0.305054)
			(end -0.12065 -0.305054)
			(stroke
				(width 0.1)
				(type default)
			)
			(layer "F.Fab")
		)
		(fp_line
			(start -0.67945 0.3048)
			(end -0.67945 -0.305054)
			(stroke
				(width 0.1)
				(type default)
			)
			(layer "F.Fab")
		)
		(fp_line
			(start -0.12065 -0.305054)
			(end -0.12065 -0.2794)
			(stroke
				(width 0.1)
				(type default)
			)
			(layer "F.Fab")
		)
		(fp_line
			(start -0.12065 -0.2794)
			(end 0.12065 -0.2794)
			(stroke
				(width 0.1)
				(type default)
			)
			(layer "F.Fab")
		)
		(fp_line
			(start -0.12065 0.2794)
			(end -0.12065 0.3048)
			(stroke
				(width 0.1)
				(type default)
			)
			(layer "F.Fab")
		)
		(fp_line
			(start -0.12065 0.3048)
			(end -0.67945 0.3048)
			(stroke
				(width 0.1)
				(type default)
			)
			(layer "F.Fab")
		)
		(fp_line
			(start 0.120396 0.2794)
			(end -0.12065 0.2794)
			(stroke
				(width 0.1)
				(type default)
			)
			(layer "F.Fab")
		)
		(fp_line
			(start 0.120396 0.3048)
			(end 0.120396 0.2794)
			(stroke
				(width 0.1)
				(type default)
			)
			(layer "F.Fab")
		)
		(fp_line
			(start 0.12065 -0.3048)
			(end 0.67945 -0.3048)
			(stroke
				(width 0.1)
				(type default)
			)
			(layer "F.Fab")
		)
		(fp_line
			(start 0.12065 -0.2794)
			(end 0.12065 -0.3048)
			(stroke
				(width 0.1)
				(type default)
			)
			(layer "F.Fab")
		)
		(fp_line
			(start 0.67945 -0.3048)
			(end 0.67945 0.3048)
			(stroke
				(width 0.1)
				(type default)
			)
			(layer "F.Fab")
		)
		(fp_line
			(start 0.67945 0.3048)
			(end 0.120396 0.3048)
			(stroke
				(width 0.1)
				(type default)
			)
			(layer "F.Fab")
		)
		(pad "1" smd circle
			(at -0.40005 0)
			(size 0 0)
			(layers "F.Cu" "F.Mask" "F.Paste")
			(net "SVID_PVDDCR_CPU1_P0_SVD_R")
		)
		(pad "2" smd circle
			(at 0.40005 0)
			(size 0 0)
			(layers "F.Cu" "F.Mask" "F.Paste")
			(net "SVID_PVDDCR_CPU1_P0_SVD_R1")
		)
	)
	(footprint ""
		(layer "F.Cu")
		(at 280.019506 -349.381572 90)
		(property "Reference" "PC172"
			(at 0 0 90)
			(layer "F.SilkS")
			(hide yes)
			(effects
				(font
					(size 1.27 1.27)
				)
			)
		)
		(property "Value" ""
			(at 0 0 90)
			(layer "F.Fab")
			(effects
				(font
					(size 1.27 1.27)
				)
			)
		)
		(duplicate_pad_numbers_are_jumpers no)
		(fp_line
			(start 0.7874 -0.4064)
			(end 0.7874 0.4064)
			(stroke
				(width 0.1524)
				(type default)
			)
			(layer "F.SilkS")
		)
		(fp_line
			(start -0.7874 -0.4064)
			(end 0.7874 -0.4064)
			(stroke
				(width 0.1524)
				(type default)
			)
			(layer "F.SilkS")
		)
		(fp_line
			(start 0.7874 0.4064)
			(end 0.452628 0.4064)
			(stroke
				(width 0.1524)
				(type default)
			)
			(layer "F.SilkS")
		)
		(fp_line
			(start -0.258572 0.4064)
			(end -0.7874 0.4064)
			(stroke
				(width 0.1524)
				(type default)
			)
			(layer "F.SilkS")
		)
		(fp_line
			(start -0.7874 0.4064)
			(end -0.7874 -0.4064)
			(stroke
				(width 0.1524)
				(type default)
			)
			(layer "F.SilkS")
		)
		(fp_line
			(start -0.12065 -0.305054)
			(end -0.12065 -0.2794)
			(stroke
				(width 0.1)
				(type default)
			)
			(layer "F.Fab")
		)
		(fp_line
			(start -0.67945 -0.305054)
			(end -0.12065 -0.305054)
			(stroke
				(width 0.1)
				(type default)
			)
			(layer "F.Fab")
		)
		(fp_line
			(start 0.67945 -0.3048)
			(end 0.67945 0.3048)
			(stroke
				(width 0.1)
				(type default)
			)
			(layer "F.Fab")
		)
		(fp_line
			(start 0.12065 -0.3048)
			(end 0.67945 -0.3048)
			(stroke
				(width 0.1)
				(type default)
			)
			(layer "F.Fab")
		)
		(fp_line
			(start 0.12065 -0.2794)
			(end 0.12065 -0.3048)
			(stroke
				(width 0.1)
				(type default)
			)
			(layer "F.Fab")
		)
		(fp_line
			(start -0.12065 -0.2794)
			(end 0.12065 -0.2794)
			(stroke
				(width 0.1)
				(type default)
			)
			(layer "F.Fab")
		)
		(fp_line
			(start 0.120396 0.2794)
			(end -0.12065 0.2794)
			(stroke
				(width 0.1)
				(type default)
			)
			(layer "F.Fab")
		)
		(fp_line
			(start -0.12065 0.2794)
			(end -0.12065 0.3048)
			(stroke
				(width 0.1)
				(type default)
			)
			(layer "F.Fab")
		)
		(fp_line
			(start 0.67945 0.3048)
			(end 0.120396 0.3048)
			(stroke
				(width 0.1)
				(type default)
			)
			(layer "F.Fab")
		)
		(fp_line
			(start 0.120396 0.3048)
			(end 0.120396 0.2794)
			(stroke
				(width 0.1)
				(type default)
			)
			(layer "F.Fab")
		)
		(fp_line
			(start -0.12065 0.3048)
			(end -0.67945 0.3048)
			(stroke
				(width 0.1)
				(type default)
			)
			(layer "F.Fab")
		)
		(fp_line
			(start -0.67945 0.3048)
			(end -0.67945 -0.305054)
			(stroke
				(width 0.1)
				(type default)
			)
			(layer "F.Fab")
		)
		(pad "1" smd circle
			(at -0.40005 0 90)
			(size 0 0)
			(layers "F.Cu" "F.Mask" "F.Paste")
			(net "PVDDIO_P0_VCC3")
		)
		(pad "2" smd circle
			(at 0.40005 0 90)
			(size 0 0)
			(layers "F.Cu" "F.Mask" "F.Paste")
			(net "GND")
		)
	)
	(footprint ""
		(layer "F.Cu")
		(at 430.02835 -398.91208 180)
		(property "Reference" "R1056"
			(at 0 0 180)
			(layer "F.SilkS")
			(hide yes)
			(effects
				(font
					(size 1.27 1.27)
				)
			)
		)
		(property "Value" ""
			(at 0 0 180)
			(layer "F.Fab")
			(effects
				(font
					(size 1.27 1.27)
				)
			)
		)
		(duplicate_pad_numbers_are_jumpers no)
		(fp_line
			(start 0.32512 0.175006)
			(end -0.32512 0.175006)
			(stroke
				(width 0.1)
				(type default)
			)
			(layer "F.Fab")
		)
		(fp_line
			(start 0.32512 -0.175006)
			(end 0.32512 0.175006)
			(stroke
				(width 0.1)
				(type default)
			)
			(layer "F.Fab")
		)
		(fp_line
			(start -0.32512 0.175006)
			(end -0.32512 -0.175006)
			(stroke
				(width 0.1)
				(type default)
			)
			(layer "F.Fab")
		)
		(fp_line
			(start -0.32512 -0.175006)
			(end 0.32512 -0.175006)
			(stroke
				(width 0.1)
				(type default)
			)
			(layer "F.Fab")
		)
		(pad "1" smd rect
			(at -0.2667 0 180)
			(size 0.3048 0.381)
			(layers "F.Cu" "F.Mask" "F.Paste")
			(net "RT_CPU0_P2_ADDR3")
		)
		(pad "2" smd rect
			(at 0.2667 0)
			(size 0.3048 0.381)
			(layers "F.Cu" "F.Mask" "F.Paste")
			(net "GND")
		)
	)
)
